FILE_TYPE = CONNECTIVITY;
{Allegro Design Entry HDL 16.6-p007 (v16-6-112F) 10/10/2012}
"PAGE_NUMBER" = 174;
0"NC";
1"SATA6G_TX_DN<3:0>";
2"SATA6G_TX_DP<3:0>";
3"SATA6G_RX_DP<3:0>";
4"SATA6G_RX_DN<3:0>";
5"GND\g";
6"GND\g";
7"P3V3\g";
8"GND\g";
9"SATA6G_RX_DP<0>";
10"SATA6G_RX_DN<0>";
11"SATA6G_RX_DN<1>";
12"SATA6G_RX_DN<3>";
13"SATA6G_RX_DP<3>";
14"SATA6G_RX_DN<2>";
15"SATA6G_RX_DP<2>";
16"SATA6G_RX_DP<1>";
17"SATA6G_P11_RX_C_DN";
18"SATA6G_P11_RX_C_DP";
19"SATA6G_P10_RX_C_DN";
20"SATA6G_P8_RX_C_DP";
21"SATA6G_P8_RX_C_DN";
22"SATA6G_P9_RX_C_DP";
23"SATA6G_P9_RX_C_DN";
24"SATA6G_P10_RX_C_DP";
25"TP_FM_QAT_CBL_PRSNT2_N";
26"SGPIO_PCH_SSATA_DOUT0_R";
27"PU_DATAIN1_SATA_2";
28"SATA6G_P11_TX_C_DP";
29"SATA6G_P11_TX_C_DN";
30"SGPIO_PCH_SSATA_CLOCK_R";
31"SGPIO_PCH_SSATA_LOAD_R";
32"SATA6G_P8_TX_C_DP";
33"SATA6G_P10_TX_C_DP";
34"SATA6G_P9_TX_C_DN";
35"SATA6G_TX_DP<3>";
36"SATA6G_TX_DN<3>";
37"SATA6G_P10_TX_C_DN";
38"SATA6G_P8_TX_C_DN";
39"SATA6G_P9_TX_C_DP";
40"SATA6G_TX_DP<0>";
41"SATA6G_TX_DP<2>";
42"SATA6G_TX_DN<2>";
43"SATA6G_TX_DP<1>";
44"SATA6G_TX_DN<1>";
45"PD_SATA2_CONTROLLER_TYPE";
46"SATA6G_TX_DN<0>";
%"TAP"
"1","(11800,3025)","0","mstr_standard","I10";
;
HDL_TAP"TRUE"
BODY_TYPE"PLUMBING"
CDS_LIB"mstr_standard";
"B \NAC \NWC"1;
"S \NAC"
BN"1"44;
%"TAP"
"1","(11800,2250)","0","mstr_standard","I11";
;
HDL_TAP"TRUE"
BODY_TYPE"PLUMBING"
CDS_LIB"mstr_standard";
"B \NAC \NWC"1;
"S \NAC"
BN"2"42;
%"CAP_A"
"2","(11225,3025)","0","dev_discrete","I12";
;
ROOM"ST_SATA"
$SEC"1"
CDS_SEC"1"
CDS_LIB"dev_discrete"
BOM_COST"ST_SATA"
CDS_LOCATION"C1L7"
MATERIAL"X7R"
VOLTAGE"25V"
PACK_TYPE"0402V"
TOLERANCE"10%"
VALUE"0.01UF"
PART_NUMBER"A36096-045"
LOCATION"C1L7";
"A"
$PN"1"34;
"B"
$PN"2"44;
%"CAP_A"
"2","(10925,3250)","0","dev_discrete","I13";
;
ROOM"ST_SATA"
$SEC"1"
CDS_SEC"1"
CDS_LIB"dev_discrete"
BOM_COST"ST_SATA"
CDS_LOCATION"C1L6"
MATERIAL"X7R"
VOLTAGE"25V"
PACK_TYPE"0402V"
TOLERANCE"10%"
VALUE"0.01UF"
PART_NUMBER"A36096-045"
LOCATION"C1L6";
"A"
$PN"1"39;
"B"
$PN"2"43;
%"CAP_A"
"2","(11025,2250)","0","dev_discrete","I14";
;
ROOM"ST_SATA"
$SEC"1"
CDS_SEC"1"
CDS_LIB"dev_discrete"
BOM_COST"ST_SATA"
CDS_LOCATION"C1L13"
MATERIAL"X7R"
VOLTAGE"25V"
PACK_TYPE"0402V"
TOLERANCE"10%"
VALUE"0.01UF"
PART_NUMBER"A36096-045"
LOCATION"C1L13";
"A"
$PN"1"37;
"B"
$PN"2"42;
%"GND"
"1","(12250,2125)","0","mstr_symbols","I15";
;
HDL_POWER"GND"
ROOM"ST_SATA"
BODY_TYPE"PLUMBING"
CDS_LIB"mstr_symbols"
SIZE"1B"
BOM_COST"ST_SATA"
VOLTAGE"0.0V";
"A\NAC"5;
%"TAP"
"1","(11950,2025)","0","mstr_standard","I16";
;
HDL_TAP"TRUE"
BODY_TYPE"PLUMBING"
CDS_LIB"mstr_standard";
"B \NAC \NWC"2;
"S \NAC"
BN"3"35;
%"TAP"
"1","(11800,1825)","0","mstr_standard","I17";
;
HDL_TAP"TRUE"
BODY_TYPE"PLUMBING"
CDS_LIB"mstr_standard";
"B \NAC \NWC"1;
"S \NAC"
BN"3"36;
%"CAP_A"
"2","(11025,1825)","0","dev_discrete","I18";
;
ROOM"ST_SATA"
$SEC"1"
CDS_SEC"1"
CDS_LIB"dev_discrete"
BOM_COST"ST_SATA"
CDS_LOCATION"C1L15"
MATERIAL"X7R"
VOLTAGE"25V"
PACK_TYPE"0402V"
TOLERANCE"10%"
VALUE"0.01UF"
PART_NUMBER"A36096-045"
LOCATION"C1L15";
"A"
$PN"1"29;
"B"
$PN"2"36;
%"CAP_A"
"2","(10750,2475)","0","dev_discrete","I19";
;
ROOM"ST_SATA"
$SEC"1"
CDS_SEC"1"
CDS_LIB"dev_discrete"
BOM_COST"ST_SATA"
CDS_LOCATION"C1L12"
MATERIAL"X7R"
VOLTAGE"25V"
PACK_TYPE"0402V"
TOLERANCE"10%"
VALUE"0.01UF"
PART_NUMBER"A36096-045"
LOCATION"C1L12";
"A"
$PN"1"33;
"B"
$PN"2"41;
%"CAP_A"
"2","(10750,2025)","0","dev_discrete","I20";
;
ROOM"ST_SATA"
$SEC"1"
CDS_SEC"1"
CDS_LIB"dev_discrete"
BOM_COST"ST_SATA"
CDS_LOCATION"C1L14"
MATERIAL"X7R"
VOLTAGE"25V"
PACK_TYPE"0402V"
TOLERANCE"10%"
VALUE"0.01UF"
PART_NUMBER"A36096-045"
LOCATION"C1L14";
"A"
$PN"1"28;
"B"
$PN"2"35;
%"GND"
"1","(9425,1850)","0","mstr_symbols","I21";
;
HDL_POWER"GND"
ROOM"ST_SATA"
BODY_TYPE"PLUMBING"
BOM_COST"ST_SATA"
SIZE"1B"
CDS_LIB"mstr_symbols"
VOLTAGE"0.0V";
"A\NAC"6;
%"P3V3"
"1","(7250,3950)","0","mstr_symbols","I24";
;
HDL_POWER"P3V3"
ROOM"ST_SATA"
BODY_TYPE"PLUMBING"
BOM_COST"ST_SATA"
SIZE"1B"
CDS_LIB"mstr_symbols"
VOLTAGE"3.3V";
"G\NAC"7;
%"RES"
"2","(7250,3600)","0","mstr_discrete","I25";
;
ROOM"ST_SATA"
CDS_LOCATION"R1L1"
$SEC"1"
CDS_SEC"1"
CDS_LIB"mstr_discrete"
BOM_COST"ST_SATA"
WATTAGE"1/16W"
MATERIAL"CHIP"
PACK_TYPE"0402"
TOLERANCE"1%"
VALUE"2.0K"
PART_NUMBER"G21796-001"
LOCATION"R1L1";
"A"
$PN"1"7;
"B"
$PN"2"27;
%"CONN36_G97614001"
"1","(8650,2725)","0","mstr_conn","I26";
;
ROOM"ST_SATA"
CDS_LOCATION"J8A2"
$SEC"1"
CDS_SEC"1"
CDS_LIB"mstr_conn"
BOM_COST"ST_SATA"
PACK_TYPE"CP"
MATERIAL"CONN"
PART_NUMBER"G97614-001"
LOCATION"J8A2";
"SIDEBAND7"
$PN"A1"25;
"SIDEBAND3"
$PN"B1"8;
"GND5"
$PN"B6"8;
"RXA2_DN"
$PN"B8"19;
"GND4"
$PN"B3"8;
"RXA2_DP"
$PN"B7"24;
"SIDEBAND5"
$PN"D1"27;
"SIDEBAND4"
$PN"C1"26;
"RXA1_DP"
$PN"A4"22;
"RXA1_DN"
$PN"A5"23;
"GND3"
$PN"A9"8;
"GND1"
$PN"A3"8;
"GND10"
$PN"D3"6;
"GND11"
$PN"D6"6;
"GND12"
$PN"D9"6;
"GND2"
$PN"A6"8;
"GND6"
$PN"B9"8;
"GND7"
$PN"C3"6;
"GND8"
$PN"C6"6;
"GND9"
$PN"C9"6;
"RXA0_DN"
$PN"B5"21;
"RXA0_DP"
$PN"B4"20;
"RXA3_DN"
$PN"A8"17;
"RXA3_DP"
$PN"A7"18;
"SIDEBAND0"
$PN"A2"30;
"SIDEBAND1"
$PN"B2"31;
"SIDEBAND2"
$PN"C2"6;
"SIDEBAND6"
$PN"D2"45;
"TXA0_DN"
$PN"D5"38;
"TXA0_DP"
$PN"D4"32;
"TXA1_DN"
$PN"C5"34;
"TXA1_DP"
$PN"C4"39;
"TXA2_DN"
$PN"D8"37;
"TXA2_DP"
$PN"D7"33;
"TXA3_DN"
$PN"C8"29;
"TXA3_DP"
$PN"C7"28;
%"GND"
"1","(7850,1875)","0","mstr_symbols","I27";
;
HDL_POWER"GND"
ROOM"ST_SATA"
BODY_TYPE"PLUMBING"
SIZE"1B"
BOM_COST"ST_SATA"
CDS_LIB"mstr_symbols"
VOLTAGE"0.0V";
"A\NAC"8;
%"CAP_A"
"2","(6525,3675)","0","dev_discrete","I28";
;
ROOM"ST_SATA"
$SEC"1"
CDS_SEC"1"
CDS_LIB"dev_discrete"
BOM_COST"ST_SATA"
CDS_LOCATION"C2L30"
MATERIAL"X7R"
VOLTAGE"25V"
PACK_TYPE"0402V"
TOLERANCE"10%"
VALUE"0.01UF"
PART_NUMBER"A36096-045"
LOCATION"C2L30";
"A"
$PN"1"9;
"B"
$PN"2"20;
%"CAP_A"
"2","(6225,3450)","0","dev_discrete","I29";
;
ROOM"ST_SATA"
$SEC"1"
CDS_SEC"1"
CDS_LIB"dev_discrete"
BOM_COST"ST_SATA"
CDS_LOCATION"C2L31"
MATERIAL"X7R"
VOLTAGE"25V"
PACK_TYPE"0402V"
TOLERANCE"10%"
VALUE"0.01UF"
PART_NUMBER"A36096-045"
LOCATION"C2L31";
"A"
$PN"1"10;
"B"
$PN"2"21;
%"TAP"
"1","(11950,3725)","0","mstr_standard","I3";
;
HDL_TAP"TRUE"
BODY_TYPE"PLUMBING"
CDS_LIB"mstr_standard";
"B \NAC \NWC"2;
"S \NAC"
BN"0"40;
%"CAP_A"
"2","(6525,3225)","0","dev_discrete","I30";
;
ROOM"ST_SATA"
$SEC"1"
CDS_SEC"1"
CDS_LIB"dev_discrete"
BOM_COST"ST_SATA"
CDS_LOCATION"C2L28"
MATERIAL"X7R"
VOLTAGE"25V"
PACK_TYPE"0402V"
TOLERANCE"10%"
VALUE"0.01UF"
PART_NUMBER"A36096-045"
LOCATION"C2L28";
"A"
$PN"1"16;
"B"
$PN"2"22;
%"CAP_A"
"2","(6600,2475)","0","dev_discrete","I31";
;
ROOM"ST_SATA"
$SEC"1"
CDS_SEC"1"
CDS_LIB"dev_discrete"
BOM_COST"ST_SATA"
CDS_LOCATION"C2L35"
MATERIAL"X7R"
VOLTAGE"25V"
PACK_TYPE"0402V"
TOLERANCE"10%"
VALUE"0.01UF"
PART_NUMBER"A36096-045"
LOCATION"C2L35";
"A"
$PN"1"15;
"B"
$PN"2"24;
%"CAP_A"
"2","(6225,3025)","0","dev_discrete","I32";
;
ROOM"ST_SATA"
$SEC"1"
CDS_SEC"1"
CDS_LIB"dev_discrete"
BOM_COST"ST_SATA"
CDS_LOCATION"C2L29"
MATERIAL"X7R"
VOLTAGE"25V"
PACK_TYPE"0402V"
TOLERANCE"10%"
VALUE"0.01UF"
PART_NUMBER"A36096-045"
LOCATION"C2L29";
"A"
$PN"1"11;
"B"
$PN"2"23;
%"TAP"
"6","(5450,3675)","0","mstr_standard","I33";
;
HDL_TAP"TRUE"
BODY_TYPE"PLUMBING"
CDS_LIB"mstr_standard";
"B \NAC \NWC"3;
"S \NAC"
BN"0"9;
%"TAP"
"6","(5600,3450)","0","mstr_standard","I34";
;
HDL_TAP"TRUE"
BODY_TYPE"PLUMBING"
CDS_LIB"mstr_standard";
"B \NAC \NWC"4;
"S \NAC"
BN"0"10;
%"TAP"
"6","(5600,3025)","0","mstr_standard","I35";
;
HDL_TAP"TRUE"
BODY_TYPE"PLUMBING"
CDS_LIB"mstr_standard";
"B \NAC \NWC"4;
"S \NAC"
BN"1"11;
%"TAP"
"6","(5450,3225)","0","mstr_standard","I36";
;
HDL_TAP"TRUE"
BODY_TYPE"PLUMBING"
CDS_LIB"mstr_standard";
"B \NAC \NWC"3;
"S \NAC"
BN"1"16;
%"TAP"
"6","(5600,2250)","0","mstr_standard","I37";
;
HDL_TAP"TRUE"
BODY_TYPE"PLUMBING"
CDS_LIB"mstr_standard";
"B \NAC \NWC"4;
"S \NAC"
BN"2"14;
%"TAP"
"6","(5450,2475)","0","mstr_standard","I38";
;
HDL_TAP"TRUE"
BODY_TYPE"PLUMBING"
CDS_LIB"mstr_standard";
"B \NAC \NWC"3;
"S \NAC"
BN"2"15;
%"CAP_A"
"2","(6300,2250)","0","dev_discrete","I39";
;
ROOM"ST_SATA"
$SEC"1"
CDS_SEC"1"
CDS_LIB"dev_discrete"
BOM_COST"ST_SATA"
CDS_LOCATION"C2L36"
MATERIAL"X7R"
VOLTAGE"25V"
PACK_TYPE"0402V"
TOLERANCE"10%"
VALUE"0.01UF"
PART_NUMBER"A36096-045"
LOCATION"C2L36";
"A"
$PN"1"14;
"B"
$PN"2"19;
%"TAP"
"1","(11950,3250)","0","mstr_standard","I4";
;
HDL_TAP"TRUE"
BODY_TYPE"PLUMBING"
CDS_LIB"mstr_standard";
"B \NAC \NWC"2;
"S \NAC"
BN"1"43;
%"CAP_A"
"2","(6600,2025)","0","dev_discrete","I40";
;
ROOM"ST_SATA"
$SEC"1"
CDS_SEC"1"
CDS_LIB"dev_discrete"
BOM_COST"ST_SATA"
CDS_LOCATION"C2L33"
MATERIAL"X7R"
VOLTAGE"25V"
PACK_TYPE"0402V"
TOLERANCE"10%"
VALUE"0.01UF"
PART_NUMBER"A36096-045"
LOCATION"C2L33";
"A"
$PN"1"13;
"B"
$PN"2"18;
%"CAP_A"
"2","(6300,1825)","0","dev_discrete","I41";
;
ROOM"ST_SATA"
$SEC"1"
CDS_SEC"1"
CDS_LIB"dev_discrete"
BOM_COST"ST_SATA"
CDS_LOCATION"C2L34"
MATERIAL"X7R"
VOLTAGE"25V"
PACK_TYPE"0402V"
TOLERANCE"10%"
VALUE"0.01UF"
PART_NUMBER"A36096-045"
LOCATION"C2L34";
"A"
$PN"1"12;
"B"
$PN"2"17;
%"TAP"
"6","(5450,2025)","0","mstr_standard","I42";
;
HDL_TAP"TRUE"
BODY_TYPE"PLUMBING"
CDS_LIB"mstr_standard";
"B \NAC \NWC"3;
"S \NAC"
BN"3"13;
%"TAP"
"6","(5600,1825)","0","mstr_standard","I43";
;
HDL_TAP"TRUE"
BODY_TYPE"PLUMBING"
CDS_LIB"mstr_standard";
"B \NAC \NWC"4;
"S \NAC"
BN"3"12;
%"RES"
"2","(12250,2425)","0","mstr_discrete","I5";
;
ROOM"ST_SATA"
CDS_LOCATION"R1L3"
$SEC"1"
CDS_SEC"1"
BOM_COST"ST_SATA"
CDS_LIB"mstr_discrete"
WATTAGE"1/16W"
MATERIAL"CHIP"
PACK_TYPE"0402"
TOLERANCE"1%"
VALUE"1.00K"
PART_NUMBER"G21796-026"
LOCATION"R1L3";
"A"
$PN"1"45;
"B"
$PN"2"5;
%"TAP"
"1","(11950,2475)","0","mstr_standard","I6";
;
HDL_TAP"TRUE"
BODY_TYPE"PLUMBING"
CDS_LIB"mstr_standard";
"B \NAC \NWC"2;
"S \NAC"
BN"2"41;
%"TAP"
"1","(11800,3475)","0","mstr_standard","I7";
;
HDL_TAP"TRUE"
BODY_TYPE"PLUMBING"
CDS_LIB"mstr_standard";
"B \NAC \NWC"1;
"S \NAC"
BN"0"46;
%"CAP_A"
"2","(11225,3475)","0","dev_discrete","I8";
;
ROOM"ST_SATA"
$SEC"1"
CDS_SEC"1"
CDS_LIB"dev_discrete"
BOM_COST"ST_SATA"
CDS_LOCATION"C1L3"
MATERIAL"X7R"
VOLTAGE"25V"
PACK_TYPE"0402V"
TOLERANCE"10%"
VALUE"0.01UF"
PART_NUMBER"A36096-045"
LOCATION"C1L3";
"A"
$PN"1"38;
"B"
$PN"2"46;
%"CAP_A"
"2","(10925,3725)","0","dev_discrete","I9";
;
ROOM"ST_SATA"
$SEC"1"
CDS_SEC"1"
CDS_LIB"dev_discrete"
BOM_COST"ST_SATA"
CDS_LOCATION"C1L2"
MATERIAL"X7R"
VOLTAGE"25V"
PACK_TYPE"0402V"
TOLERANCE"10%"
VALUE"0.01UF"
PART_NUMBER"A36096-045"
LOCATION"C1L2";
"A"
$PN"1"32;
"B"
$PN"2"40;
END.
